# T6G (Grand Teton) — schematic netlist excerpt (pin names and nets, part order shuffled) for the footprints in the layout excerpt that follows; sources: Cadence DE-HDL packaged netlist, KiCad conversion of 04192023_DAF0TMB3IC0_F0TG_MB_C_brd_V02_OCP.brd

PC6513  Q_CAPP  390UF 2.5V 20% ALUM  pkg SMLF  page 360 : A = P1V8_CPU0_RT_1D ; B = GND
C906  Q_CAP_DIFFBUS  DIFF BUS_0.22UF 6.3V 20% X6S  pkg C0201  page 63 : \1\ = P5E_CPU0_P0_TX_C_DN<13> ; \2\ = P5E_CPU0_P0_TX_DN<13>
PC110  Q_CAP  2.2UF 10V 10% X6S  pkg C0402  page 202 : A = PVDDCR_CPU1_P0_VCC3 ; B = GND
R1065  Q_RES  4.7K 5% EMPTY  pkg 0201LF  page 298 : A = P1V8_CPU0_RT_1D ; B = RST_RT_CPU0_P2_RESET_R_N

(kicad_pcb
	(version 20260206)
	(generator "pcbnew")
	(generator_version "10.0")
	(general
		(thickness 1.6)
		(legacy_teardrops no)
	)
	(paper "A4")
	(title_block
		(title "04192023_DAF0TMB3IC0_F0TG_MB_C_brd_V02_OCP.brd")
		(comment 1 "Grand Teton / footprints 2303-2306 of 8354")
	)
	(layers
		(0 "F.Cu" signal "TOP")
		(4 "In1.Cu" signal "GND")
		(6 "In2.Cu" signal "IN1")
		(8 "In3.Cu" signal "GND1")
		(10 "In4.Cu" signal "IN2")
		(12 "In5.Cu" signal "GND2")
		(14 "In6.Cu" signal "IN3")
		(16 "In7.Cu" signal "GND3")
		(18 "In8.Cu" signal "VCC")
		(20 "In9.Cu" signal "VCC1")
		(22 "In10.Cu" signal "GND4")
		(24 "In11.Cu" signal "IN4")
		(26 "In12.Cu" signal "GND5")
		(28 "In13.Cu" signal "IN5")
		(30 "In14.Cu" signal "GND6")
		(32 "In15.Cu" signal "IN6")
		(34 "In16.Cu" signal "GND7")
		(2 "B.Cu" signal "BOTTOM")
		(9 "F.Adhes" user "F.Adhesive")
		(11 "B.Adhes" user "B.Adhesive")
		(13 "F.Paste" user "Package Geometry/Pastemask Top")
		(15 "B.Paste" user "Package Geometry/Pastemask Bottom")
		(5 "F.SilkS" user "Ref Des/Silkscreen Top")
		(7 "B.SilkS" user "Ref Des/Silkscreen Bottom")
		(1 "F.Mask" user "Board Geometry/Soldermask Top")
		(3 "B.Mask" user "Board Geometry/Soldermask Bottom")
		(17 "Dwgs.User" user "User.Drawings")
		(19 "Cmts.User" user "User.Comments")
		(21 "Eco1.User" user "User.Eco1")
		(23 "Eco2.User" user "User.Eco2")
		(25 "Edge.Cuts" user "Board Geometry/Outline")
		(27 "Margin" user)
		(31 "F.CrtYd" user "Package Geometry/Place Bound Top")
		(29 "B.CrtYd" user "Package Geometry/Place Bound Bottom")
		(35 "F.Fab" user "Ref Des/Assembly Top")
		(33 "B.Fab" user "Ref Des/Assembly Bottom")
	)
	(footprint ""
		(layer "F.Cu")
		(at 400.315684 -403.818852 -90)
		(property "Reference" "R1065"
			(at 0 0 270)
			(layer "F.SilkS")
			(hide yes)
			(effects
				(font
					(size 1.27 1.27)
				)
			)
		)
		(property "Value" ""
			(at 0 0 270)
			(layer "F.Fab")
			(effects
				(font
					(size 1.27 1.27)
				)
			)
		)
		(duplicate_pad_numbers_are_jumpers no)
		(fp_line
			(start -0.32512 0.175006)
			(end -0.32512 -0.175006)
			(stroke
				(width 0.1)
				(type default)
			)
			(layer "F.Fab")
		)
		(fp_line
			(start 0.32512 0.175006)
			(end -0.32512 0.175006)
			(stroke
				(width 0.1)
				(type default)
			)
			(layer "F.Fab")
		)
		(fp_line
			(start -0.32512 -0.175006)
			(end 0.32512 -0.175006)
			(stroke
				(width 0.1)
				(type default)
			)
			(layer "F.Fab")
		)
		(fp_line
			(start 0.32512 -0.175006)
			(end 0.32512 0.175006)
			(stroke
				(width 0.1)
				(type default)
			)
			(layer "F.Fab")
		)
		(pad "1" smd rect
			(at -0.2667 0 270)
			(size 0.3048 0.381)
			(layers "F.Cu" "F.Mask" "F.Paste")
			(net "P1V8_CPU0_RT_1D")
		)
		(pad "2" smd rect
			(at 0.2667 0 90)
			(size 0.3048 0.381)
			(layers "F.Cu" "F.Mask" "F.Paste")
			(net "RST_RT_CPU0_P2_RESET_R_N")
		)
	)
	(footprint ""
		(layer "F.Cu")
		(at 314.66282 -337.660488 90)
		(property "Reference" "PC110"
			(at 0 0 90)
			(layer "F.SilkS")
			(hide yes)
			(effects
				(font
					(size 1.27 1.27)
				)
			)
		)
		(property "Value" ""
			(at 0 0 90)
			(layer "F.Fab")
			(effects
				(font
					(size 1.27 1.27)
				)
			)
		)
		(duplicate_pad_numbers_are_jumpers no)
		(fp_line
			(start 0.7874 -0.4064)
			(end 0.7874 0.4064)
			(stroke
				(width 0.1524)
				(type default)
			)
			(layer "F.SilkS")
		)
		(fp_line
			(start -0.7874 -0.4064)
			(end 0.7874 -0.4064)
			(stroke
				(width 0.1524)
				(type default)
			)
			(layer "F.SilkS")
		)
		(fp_line
			(start 0.7874 0.4064)
			(end 0.413512 0.4064)
			(stroke
				(width 0.1524)
				(type default)
			)
			(layer "F.SilkS")
		)
		(fp_line
			(start -0.272288 0.4064)
			(end -0.7874 0.4064)
			(stroke
				(width 0.1524)
				(type default)
			)
			(layer "F.SilkS")
		)
		(fp_line
			(start -0.7874 0.4064)
			(end -0.7874 -0.4064)
			(stroke
				(width 0.1524)
				(type default)
			)
			(layer "F.SilkS")
		)
		(fp_line
			(start -0.12065 -0.305054)
			(end -0.12065 -0.2794)
			(stroke
				(width 0.1)
				(type default)
			)
			(layer "F.Fab")
		)
		(fp_line
			(start -0.67945 -0.305054)
			(end -0.12065 -0.305054)
			(stroke
				(width 0.1)
				(type default)
			)
			(layer "F.Fab")
		)
		(fp_line
			(start 0.67945 -0.3048)
			(end 0.67945 0.3048)
			(stroke
				(width 0.1)
				(type default)
			)
			(layer "F.Fab")
		)
		(fp_line
			(start 0.12065 -0.3048)
			(end 0.67945 -0.3048)
			(stroke
				(width 0.1)
				(type default)
			)
			(layer "F.Fab")
		)
		(fp_line
			(start 0.12065 -0.2794)
			(end 0.12065 -0.3048)
			(stroke
				(width 0.1)
				(type default)
			)
			(layer "F.Fab")
		)
		(fp_line
			(start -0.12065 -0.2794)
			(end 0.12065 -0.2794)
			(stroke
				(width 0.1)
				(type default)
			)
			(layer "F.Fab")
		)
		(fp_line
			(start 0.120396 0.2794)
			(end -0.12065 0.2794)
			(stroke
				(width 0.1)
				(type default)
			)
			(layer "F.Fab")
		)
		(fp_line
			(start -0.12065 0.2794)
			(end -0.12065 0.3048)
			(stroke
				(width 0.1)
				(type default)
			)
			(layer "F.Fab")
		)
		(fp_line
			(start 0.67945 0.3048)
			(end 0.120396 0.3048)
			(stroke
				(width 0.1)
				(type default)
			)
			(layer "F.Fab")
		)
		(fp_line
			(start 0.120396 0.3048)
			(end 0.120396 0.2794)
			(stroke
				(width 0.1)
				(type default)
			)
			(layer "F.Fab")
		)
		(fp_line
			(start -0.12065 0.3048)
			(end -0.67945 0.3048)
			(stroke
				(width 0.1)
				(type default)
			)
			(layer "F.Fab")
		)
		(fp_line
			(start -0.67945 0.3048)
			(end -0.67945 -0.305054)
			(stroke
				(width 0.1)
				(type default)
			)
			(layer "F.Fab")
		)
		(pad "1" smd circle
			(at -0.40005 0 90)
			(size 0 0)
			(layers "F.Cu" "F.Mask" "F.Paste")
			(net "PVDDCR_CPU1_P0_VCC3")
		)
		(pad "2" smd circle
			(at 0.40005 0 90)
			(size 0 0)
			(layers "F.Cu" "F.Mask" "F.Paste")
			(net "GND")
		)
	)
	(footprint ""
		(layer "F.Cu")
		(at 324.516496 -378.95403 -90)
		(property "Reference" "C906"
			(at 0 0 270)
			(layer "F.SilkS")
			(hide yes)
			(effects
				(font
					(size 1.27 1.27)
				)
			)
		)
		(property "Value" ""
			(at 0 0 270)
			(layer "F.Fab")
			(effects
				(font
					(size 1.27 1.27)
				)
			)
		)
		(duplicate_pad_numbers_are_jumpers no)
		(fp_line
			(start -0.299974 0.150114)
			(end -0.299974 -0.150114)
			(stroke
				(width 0.1)
				(type default)
			)
			(layer "F.Fab")
		)
		(fp_line
			(start 0.299974 0.150114)
			(end -0.299974 0.150114)
			(stroke
				(width 0.1)
				(type default)
			)
			(layer "F.Fab")
		)
		(fp_line
			(start -0.299974 -0.150114)
			(end 0.299974 -0.150114)
			(stroke
				(width 0.1)
				(type default)
			)
			(layer "F.Fab")
		)
		(fp_line
			(start 0.299974 -0.150114)
			(end 0.299974 0.150114)
			(stroke
				(width 0.1)
				(type default)
			)
			(layer "F.Fab")
		)
		(pad "1" smd rect
			(at -0.2667 0 270)
			(size 0.3048 0.381)
			(layers "F.Cu" "F.Mask" "F.Paste")
			(net "P5E_CPU0_P0_TX_C_DN<13>")
		)
		(pad "2" smd rect
			(at 0.2667 0 270)
			(size 0.3048 0.381)
			(layers "F.Cu" "F.Mask" "F.Paste")
			(net "P5E_CPU0_P0_TX_DN<13>")
		)
	)
	(footprint ""
		(layer "F.Cu")
		(at 241.403378 -315.82868 90)
		(property "Reference" "PC6513"
			(at -1.75768 9.956292 90)
			(unlocked yes)
			(layer "F.SilkS")
			(effects
				(font
					(size 0.7874 0.5842)
					(thickness 0.1524)
				)
				(justify left)
			)
		)
		(property "Value" ""
			(at 0 0 90)
			(layer "F.Fab")
			(effects
				(font
					(size 1.27 1.27)
				)
			)
		)
		(duplicate_pad_numbers_are_jumpers no)
		(fp_line
			(start 2.750058 -2.750058)
			(end -1.988058 -2.750058)
			(stroke
				(width 0.1524)
				(type default)
			)
			(layer "F.SilkS")
		)
		(fp_line
			(start -1.988058 -2.750058)
			(end -2.750058 -1.988058)
			(stroke
				(width 0.1524)
				(type default)
			)
			(layer "F.SilkS")
		)
		(fp_line
			(start -2.750058 -1.988058)
			(end -2.750058 -0.9398)
			(stroke
				(width 0.1524)
				(type default)
			)
			(layer "F.SilkS")
		)
		(fp_line
			(start 2.750058 -0.9398)
			(end 2.750058 -2.750058)
			(stroke
				(width 0.1524)
				(type default)
			)
			(layer "F.SilkS")
		)
		(fp_line
			(start -2.750058 0.9398)
			(end -2.750058 1.988058)
			(stroke
				(width 0.1524)
				(type default)
			)
			(layer "F.SilkS")
		)
		(fp_line
			(start -2.750058 1.988058)
			(end -1.988058 2.750058)
			(stroke
				(width 0.1524)
				(type default)
			)
			(layer "F.SilkS")
		)
		(fp_line
			(start 2.750058 2.750058)
			(end 2.750058 0.9398)
			(stroke
				(width 0.1524)
				(type default)
			)
			(layer "F.SilkS")
		)
		(fp_line
			(start -1.988058 2.750058)
			(end 2.750058 2.750058)
			(stroke
				(width 0.1524)
				(type default)
			)
			(layer "F.SilkS")
		)
		(fp_line
			(start 2.750058 -2.750058)
			(end -2.750058 -2.750058)
			(stroke
				(width 0.1)
				(type default)
			)
			(layer "F.Fab")
		)
		(fp_line
			(start -2.750058 -2.750058)
			(end -2.750058 2.750058)
			(stroke
				(width 0.1)
				(type default)
			)
			(layer "F.Fab")
		)
		(fp_line
			(start 2.750058 2.750058)
			(end 2.750058 -2.750058)
			(stroke
				(width 0.1)
				(type default)
			)
			(layer "F.Fab")
		)
		(fp_line
			(start -2.750058 2.750058)
			(end 2.750058 2.750058)
			(stroke
				(width 0.1)
				(type default)
			)
			(layer "F.Fab")
		)
		(pad "1" smd rect
			(at -2.199894 0 180)
			(size 1.6002 3.0226)
			(layers "F.Cu" "F.Mask" "F.Paste")
			(net "P1V8_CPU0_RT_1D")
		)
		(pad "2" smd rect
			(at 2.199894 0 180)
			(size 1.6002 3.0226)
			(layers "F.Cu" "F.Mask" "F.Paste")
			(net "GND")
		)
	)
)
